(kicad_pcb
	(version 20260206)
	(generator "pcbnew")
	(generator_version "10.0")
	(general
		(thickness 1.6)
		(legacy_teardrops no)
	)
	(paper "A4")
	(title_block
		(title "12092022_DA0F0TFB6D0_F0T_FAN_BOARD_MP5048_D_brd_v02_OCP.brd")
		(comment 1 "Grand Teton / footprints 638-643 of 924")
	)
	(layers
		(0 "F.Cu" signal "TOP")
		(4 "In1.Cu" signal "GND")
		(6 "In2.Cu" signal "IN1")
		(8 "In3.Cu" signal "IN2")
		(10 "In4.Cu" signal "GND1")
		(2 "B.Cu" signal "BOTTOM")
		(9 "F.Adhes" user "F.Adhesive")
		(11 "B.Adhes" user "B.Adhesive")
		(13 "F.Paste" user "Package Geometry/Pastemask Top")
		(15 "B.Paste" user "Package Geometry/Pastemask Bottom")
		(5 "F.SilkS" user "Ref Des/Silkscreen Top")
		(7 "B.SilkS" user "Ref Des/Silkscreen Bottom")
		(1 "F.Mask" user "Board Geometry/Soldermask Top")
		(3 "B.Mask" user "Board Geometry/Soldermask Bottom")
		(17 "Dwgs.User" user "User.Drawings")
		(19 "Cmts.User" user "User.Comments")
		(21 "Eco1.User" user "User.Eco1")
		(23 "Eco2.User" user "User.Eco2")
		(25 "Edge.Cuts" user "Board Geometry/Outline")
		(27 "Margin" user)
		(31 "F.CrtYd" user "Package Geometry/Place Bound Top")
		(29 "B.CrtYd" user "Package Geometry/Place Bound Bottom")
		(35 "F.Fab" user "Ref Des/Assembly Top")
		(33 "B.Fab" user "Ref Des/Assembly Bottom")
	)
	(footprint ""
		(layer "F.Cu")
		(at 15.377922 -103.855012 180)
		(property "Reference" "D134"
			(at 5.344922 -0.376682 0)
			(unlocked yes)
			(layer "F.SilkS")
			(effects
				(font
					(size 0.7874 0.5842)
					(thickness 0.1524)
				)
				(justify left)
			)
		)
		(property "Value" ""
			(at 0 0 180)
			(layer "F.Fab")
			(effects
				(font
					(size 1.27 1.27)
				)
			)
		)
		(duplicate_pad_numbers_are_jumpers no)
		(fp_line
			(start 2.032 0.7112)
			(end -1.651 0.7112)
			(stroke
				(width 0.1524)
				(type default)
			)
			(layer "F.SilkS")
		)
		(fp_line
			(start 2.032 -0.7112)
			(end 2.032 0.7112)
			(stroke
				(width 0.1524)
				(type default)
			)
			(layer "F.SilkS")
		)
		(fp_line
			(start 1.905 -0.6858)
			(end 1.905 0.6858)
			(stroke
				(width 0.1524)
				(type default)
			)
			(layer "F.SilkS")
		)
		(fp_line
			(start 1.778 0.6858)
			(end 1.778 -0.6858)
			(stroke
				(width 0.1524)
				(type default)
			)
			(layer "F.SilkS")
		)
		(fp_line
			(start 1.651 -0.6858)
			(end 1.651 0.6858)
			(stroke
				(width 0.1524)
				(type default)
			)
			(layer "F.SilkS")
		)
		(fp_line
			(start 0.299974 -0.500126)
			(end 0.299974 0.500126)
			(stroke
				(width 0.1524)
				(type default)
			)
			(layer "F.SilkS")
		)
		(fp_line
			(start 0.199898 0)
			(end -0.299974 -0.500126)
			(stroke
				(width 0.1524)
				(type default)
			)
			(layer "F.SilkS")
		)
		(fp_line
			(start -0.299974 0.500126)
			(end 0.199898 0)
			(stroke
				(width 0.1524)
				(type default)
			)
			(layer "F.SilkS")
		)
		(fp_line
			(start -0.299974 -0.500126)
			(end -0.299974 0.500126)
			(stroke
				(width 0.1524)
				(type default)
			)
			(layer "F.SilkS")
		)
		(fp_line
			(start -1.651 0.7112)
			(end -1.651 -0.7112)
			(stroke
				(width 0.1524)
				(type default)
			)
			(layer "F.SilkS")
		)
		(fp_line
			(start -1.651 -0.7112)
			(end 2.032 -0.7112)
			(stroke
				(width 0.1524)
				(type default)
			)
			(layer "F.SilkS")
		)
		(fp_line
			(start 1.35001 0.175006)
			(end 0.899922 0.175006)
			(stroke
				(width 0.1)
				(type default)
			)
			(layer "F.Fab")
		)
		(fp_line
			(start 1.35001 -0.225044)
			(end 1.35001 0.175006)
			(stroke
				(width 0.1)
				(type default)
			)
			(layer "F.Fab")
		)
		(fp_line
			(start 0.899922 0.700024)
			(end -0.899922 0.700024)
			(stroke
				(width 0.1)
				(type default)
			)
			(layer "F.Fab")
		)
		(fp_line
			(start 0.899922 0.175006)
			(end 0.899922 0.700024)
			(stroke
				(width 0.1)
				(type default)
			)
			(layer "F.Fab")
		)
		(fp_line
			(start 0.899922 -0.225044)
			(end 1.35001 -0.225044)
			(stroke
				(width 0.1)
				(type default)
			)
			(layer "F.Fab")
		)
		(fp_line
			(start 0.899922 -0.700024)
			(end 0.899922 -0.225044)
			(stroke
				(width 0.1)
				(type default)
			)
			(layer "F.Fab")
		)
		(fp_line
			(start 0.299974 -0.500126)
			(end 0.299974 0.500126)
			(stroke
				(width 0.1)
				(type default)
			)
			(layer "F.Fab")
		)
		(fp_line
			(start 0.199898 0)
			(end -0.299974 -0.500126)
			(stroke
				(width 0.1)
				(type default)
			)
			(layer "F.Fab")
		)
		(fp_line
			(start -0.299974 0.500126)
			(end 0.199898 0)
			(stroke
				(width 0.1)
				(type default)
			)
			(layer "F.Fab")
		)
		(fp_line
			(start -0.299974 -0.500126)
			(end -0.299974 0.500126)
			(stroke
				(width 0.1)
				(type default)
			)
			(layer "F.Fab")
		)
		(fp_line
			(start -0.899922 0.700024)
			(end -0.899922 0.175006)
			(stroke
				(width 0.1)
				(type default)
			)
			(layer "F.Fab")
		)
		(fp_line
			(start -0.899922 0.175006)
			(end -1.35001 0.175006)
			(stroke
				(width 0.1)
				(type default)
			)
			(layer "F.Fab")
		)
		(fp_line
			(start -0.899922 -0.225044)
			(end -0.899922 -0.700024)
			(stroke
				(width 0.1)
				(type default)
			)
			(layer "F.Fab")
		)
		(fp_line
			(start -0.899922 -0.700024)
			(end 0.899922 -0.700024)
			(stroke
				(width 0.1)
				(type default)
			)
			(layer "F.Fab")
		)
		(fp_line
			(start -1.35001 0.175006)
			(end -1.35001 -0.225044)
			(stroke
				(width 0.1)
				(type default)
			)
			(layer "F.Fab")
		)
		(fp_line
			(start -1.35001 -0.225044)
			(end -0.899922 -0.225044)
			(stroke
				(width 0.1)
				(type default)
			)
			(layer "F.Fab")
		)
		(fp_text user "-"
			(at 1.153922 -1.207262 180)
			(unlocked yes)
			(layer "F.SilkS")
			(effects
				(font
					(size 1.905 1.4224)
					(thickness 0.1524)
				)
				(justify left)
			)
		)
		(fp_text user "+"
			(at -2.656078 -1.207262 180)
			(unlocked yes)
			(layer "F.SilkS")
			(effects
				(font
					(size 1.905 1.4224)
					(thickness 0.1524)
				)
				(justify left)
			)
		)
		(fp_text user "-"
			(at 1.8288 -0.24765 180)
			(unlocked yes)
			(layer "F.Fab")
			(effects
				(font
					(size 1.905 1.4224)
					(thickness 0.1524)
				)
				(justify left)
			)
		)
		(fp_text user "+"
			(at -2.794 -0.19685 180)
			(unlocked yes)
			(layer "F.Fab")
			(effects
				(font
					(size 1.905 1.4224)
					(thickness 0.1524)
				)
				(justify left)
			)
		)
		(pad "1" smd rect
			(at -1.0922 0)
			(size 0.8128 0.8636)
			(layers "F.Cu" "F.Mask" "F.Paste")
			(net "FAN_5_TACH_IL_R")
		)
		(pad "2" smd rect
			(at 1.0922 0 180)
			(size 0.8128 0.8636)
			(layers "F.Cu" "F.Mask" "F.Paste")
			(net "FAN_5_TACH_IL_D")
		)
	)
	(footprint ""
		(layer "F.Cu")
		(at 14.0589 -125.857 180)
		(property "Reference" "R5588"
			(at 0 0 180)
			(layer "F.SilkS")
			(hide yes)
			(effects
				(font
					(size 1.27 1.27)
				)
			)
		)
		(property "Value" ""
			(at 0 0 180)
			(layer "F.Fab")
			(effects
				(font
					(size 1.27 1.27)
				)
			)
		)
		(duplicate_pad_numbers_are_jumpers no)
		(fp_line
			(start 0.7874 0.4064)
			(end -0.7874 0.4064)
			(stroke
				(width 0.1524)
				(type default)
			)
			(layer "F.SilkS")
		)
		(fp_line
			(start 0.7874 -0.4064)
			(end 0.7874 0.4064)
			(stroke
				(width 0.1524)
				(type default)
			)
			(layer "F.SilkS")
		)
		(fp_line
			(start -0.7874 0.4064)
			(end -0.7874 -0.4064)
			(stroke
				(width 0.1524)
				(type default)
			)
			(layer "F.SilkS")
		)
		(fp_line
			(start -0.7874 -0.4064)
			(end 0.7874 -0.4064)
			(stroke
				(width 0.1524)
				(type default)
			)
			(layer "F.SilkS")
		)
		(fp_line
			(start 0.67945 0.3048)
			(end 0.120396 0.3048)
			(stroke
				(width 0.1)
				(type default)
			)
			(layer "F.Fab")
		)
		(fp_line
			(start 0.67945 -0.3048)
			(end 0.67945 0.3048)
			(stroke
				(width 0.1)
				(type default)
			)
			(layer "F.Fab")
		)
		(fp_line
			(start 0.12065 -0.2794)
			(end 0.12065 -0.3048)
			(stroke
				(width 0.1)
				(type default)
			)
			(layer "F.Fab")
		)
		(fp_line
			(start 0.12065 -0.3048)
			(end 0.67945 -0.3048)
			(stroke
				(width 0.1)
				(type default)
			)
			(layer "F.Fab")
		)
		(fp_line
			(start 0.120396 0.3048)
			(end 0.120396 0.2794)
			(stroke
				(width 0.1)
				(type default)
			)
			(layer "F.Fab")
		)
		(fp_line
			(start 0.120396 0.2794)
			(end -0.12065 0.2794)
			(stroke
				(width 0.1)
				(type default)
			)
			(layer "F.Fab")
		)
		(fp_line
			(start -0.12065 0.3048)
			(end -0.67945 0.3048)
			(stroke
				(width 0.1)
				(type default)
			)
			(layer "F.Fab")
		)
		(fp_line
			(start -0.12065 0.2794)
			(end -0.12065 0.3048)
			(stroke
				(width 0.1)
				(type default)
			)
			(layer "F.Fab")
		)
		(fp_line
			(start -0.12065 -0.2794)
			(end 0.12065 -0.2794)
			(stroke
				(width 0.1)
				(type default)
			)
			(layer "F.Fab")
		)
		(fp_line
			(start -0.12065 -0.305054)
			(end -0.12065 -0.2794)
			(stroke
				(width 0.1)
				(type default)
			)
			(layer "F.Fab")
		)
		(fp_line
			(start -0.67945 0.3048)
			(end -0.67945 -0.305054)
			(stroke
				(width 0.1)
				(type default)
			)
			(layer "F.Fab")
		)
		(fp_line
			(start -0.67945 -0.305054)
			(end -0.12065 -0.305054)
			(stroke
				(width 0.1)
				(type default)
			)
			(layer "F.Fab")
		)
		(pad "1" smd rect
			(at -0.40005 0)
			(size 0.4572 0.508)
			(layers "F.Cu" "F.Mask" "F.Paste")
			(net "FAN_4_TACH_OL")
		)
		(pad "2" smd rect
			(at 0.40005 0)
			(size 0.4572 0.508)
			(layers "F.Cu" "F.Mask" "F.Paste")
			(net "FAN_4_TACH_OL_R2")
		)
	)
	(footprint ""
		(layer "F.Cu")
		(at 14.351 -295.656)
		(property "Reference" "R5245"
			(at 0 0 0)
			(layer "F.SilkS")
			(hide yes)
			(effects
				(font
					(size 1.27 1.27)
				)
			)
		)
		(property "Value" ""
			(at 0 0 0)
			(layer "F.Fab")
			(effects
				(font
					(size 1.27 1.27)
				)
			)
		)
		(duplicate_pad_numbers_are_jumpers no)
		(fp_line
			(start -0.7874 -0.4064)
			(end 0.7874 -0.4064)
			(stroke
				(width 0.1524)
				(type default)
			)
			(layer "F.SilkS")
		)
		(fp_line
			(start -0.7874 0.4064)
			(end -0.7874 -0.4064)
			(stroke
				(width 0.1524)
				(type default)
			)
			(layer "F.SilkS")
		)
		(fp_line
			(start 0.7874 -0.4064)
			(end 0.7874 0.4064)
			(stroke
				(width 0.1524)
				(type default)
			)
			(layer "F.SilkS")
		)
		(fp_line
			(start 0.7874 0.4064)
			(end -0.7874 0.4064)
			(stroke
				(width 0.1524)
				(type default)
			)
			(layer "F.SilkS")
		)
		(fp_line
			(start -0.67945 -0.305054)
			(end -0.12065 -0.305054)
			(stroke
				(width 0.1)
				(type default)
			)
			(layer "F.Fab")
		)
		(fp_line
			(start -0.67945 0.3048)
			(end -0.67945 -0.305054)
			(stroke
				(width 0.1)
				(type default)
			)
			(layer "F.Fab")
		)
		(fp_line
			(start -0.12065 -0.305054)
			(end -0.12065 -0.2794)
			(stroke
				(width 0.1)
				(type default)
			)
			(layer "F.Fab")
		)
		(fp_line
			(start -0.12065 -0.2794)
			(end 0.12065 -0.2794)
			(stroke
				(width 0.1)
				(type default)
			)
			(layer "F.Fab")
		)
		(fp_line
			(start -0.12065 0.2794)
			(end -0.12065 0.3048)
			(stroke
				(width 0.1)
				(type default)
			)
			(layer "F.Fab")
		)
		(fp_line
			(start -0.12065 0.3048)
			(end -0.67945 0.3048)
			(stroke
				(width 0.1)
				(type default)
			)
			(layer "F.Fab")
		)
		(fp_line
			(start 0.120396 0.2794)
			(end -0.12065 0.2794)
			(stroke
				(width 0.1)
				(type default)
			)
			(layer "F.Fab")
		)
		(fp_line
			(start 0.120396 0.3048)
			(end 0.120396 0.2794)
			(stroke
				(width 0.1)
				(type default)
			)
			(layer "F.Fab")
		)
		(fp_line
			(start 0.12065 -0.3048)
			(end 0.67945 -0.3048)
			(stroke
				(width 0.1)
				(type default)
			)
			(layer "F.Fab")
		)
		(fp_line
			(start 0.12065 -0.2794)
			(end 0.12065 -0.3048)
			(stroke
				(width 0.1)
				(type default)
			)
			(layer "F.Fab")
		)
		(fp_line
			(start 0.67945 -0.3048)
			(end 0.67945 0.3048)
			(stroke
				(width 0.1)
				(type default)
			)
			(layer "F.Fab")
		)
		(fp_line
			(start 0.67945 0.3048)
			(end 0.120396 0.3048)
			(stroke
				(width 0.1)
				(type default)
			)
			(layer "F.Fab")
		)
		(pad "1" smd circle
			(at -0.40005 0)
			(size 0 0)
			(layers "F.Cu" "F.Mask" "F.Paste")
			(net "SMB_FAN7_SDA_R")
		)
		(pad "2" smd circle
			(at 0.40005 0)
			(size 0 0)
			(layers "F.Cu" "F.Mask" "F.Paste")
			(net "SMB_FAN7_SDA")
		)
	)
	(footprint ""
		(layer "F.Cu")
		(at 25.527 -125.349)
		(property "Reference" "R4948"
			(at 0 0 0)
			(layer "F.SilkS")
			(hide yes)
			(effects
				(font
					(size 1.27 1.27)
				)
			)
		)
		(property "Value" ""
			(at 0 0 0)
			(layer "F.Fab")
			(effects
				(font
					(size 1.27 1.27)
				)
			)
		)
		(duplicate_pad_numbers_are_jumpers no)
		(fp_line
			(start -0.7874 -0.4064)
			(end 0.7874 -0.4064)
			(stroke
				(width 0.1524)
				(type default)
			)
			(layer "F.SilkS")
		)
		(fp_line
			(start -0.7874 0.4064)
			(end -0.7874 -0.4064)
			(stroke
				(width 0.1524)
				(type default)
			)
			(layer "F.SilkS")
		)
		(fp_line
			(start 0.7874 -0.4064)
			(end 0.7874 0.4064)
			(stroke
				(width 0.1524)
				(type default)
			)
			(layer "F.SilkS")
		)
		(fp_line
			(start 0.7874 0.4064)
			(end -0.7874 0.4064)
			(stroke
				(width 0.1524)
				(type default)
			)
			(layer "F.SilkS")
		)
		(fp_line
			(start -0.67945 -0.305054)
			(end -0.12065 -0.305054)
			(stroke
				(width 0.1)
				(type default)
			)
			(layer "F.Fab")
		)
		(fp_line
			(start -0.67945 0.3048)
			(end -0.67945 -0.305054)
			(stroke
				(width 0.1)
				(type default)
			)
			(layer "F.Fab")
		)
		(fp_line
			(start -0.12065 -0.305054)
			(end -0.12065 -0.2794)
			(stroke
				(width 0.1)
				(type default)
			)
			(layer "F.Fab")
		)
		(fp_line
			(start -0.12065 -0.2794)
			(end 0.12065 -0.2794)
			(stroke
				(width 0.1)
				(type default)
			)
			(layer "F.Fab")
		)
		(fp_line
			(start -0.12065 0.2794)
			(end -0.12065 0.3048)
			(stroke
				(width 0.1)
				(type default)
			)
			(layer "F.Fab")
		)
		(fp_line
			(start -0.12065 0.3048)
			(end -0.67945 0.3048)
			(stroke
				(width 0.1)
				(type default)
			)
			(layer "F.Fab")
		)
		(fp_line
			(start 0.120396 0.2794)
			(end -0.12065 0.2794)
			(stroke
				(width 0.1)
				(type default)
			)
			(layer "F.Fab")
		)
		(fp_line
			(start 0.120396 0.3048)
			(end 0.120396 0.2794)
			(stroke
				(width 0.1)
				(type default)
			)
			(layer "F.Fab")
		)
		(fp_line
			(start 0.12065 -0.3048)
			(end 0.67945 -0.3048)
			(stroke
				(width 0.1)
				(type default)
			)
			(layer "F.Fab")
		)
		(fp_line
			(start 0.12065 -0.2794)
			(end 0.12065 -0.3048)
			(stroke
				(width 0.1)
				(type default)
			)
			(layer "F.Fab")
		)
		(fp_line
			(start 0.67945 -0.3048)
			(end 0.67945 0.3048)
			(stroke
				(width 0.1)
				(type default)
			)
			(layer "F.Fab")
		)
		(fp_line
			(start 0.67945 0.3048)
			(end 0.120396 0.3048)
			(stroke
				(width 0.1)
				(type default)
			)
			(layer "F.Fab")
		)
		(pad "1" smd circle
			(at -0.40005 0)
			(size 0 0)
			(layers "F.Cu" "F.Mask" "F.Paste")
			(net "MAX31790_U330_PWM_START0")
		)
		(pad "2" smd circle
			(at 0.40005 0)
			(size 0 0)
			(layers "F.Cu" "F.Mask" "F.Paste")
			(net "P3V3_AUX")
		)
	)
	(footprint ""
		(layer "F.Cu")
		(at 16.393922 -286.6771)
		(property "Reference" "C2056"
			(at 0 0 0)
			(layer "F.SilkS")
			(hide yes)
			(effects
				(font
					(size 1.27 1.27)
				)
			)
		)
		(property "Value" ""
			(at 0 0 0)
			(layer "F.Fab")
			(effects
				(font
					(size 1.27 1.27)
				)
			)
		)
		(duplicate_pad_numbers_are_jumpers no)
		(fp_line
			(start -0.7874 -0.4064)
			(end 0.7874 -0.4064)
			(stroke
				(width 0.1524)
				(type default)
			)
			(layer "F.SilkS")
		)
		(fp_line
			(start -0.7874 0.4064)
			(end -0.7874 -0.4064)
			(stroke
				(width 0.1524)
				(type default)
			)
			(layer "F.SilkS")
		)
		(fp_line
			(start 0.7874 -0.4064)
			(end 0.7874 0.4064)
			(stroke
				(width 0.1524)
				(type default)
			)
			(layer "F.SilkS")
		)
		(fp_line
			(start 0.7874 0.4064)
			(end -0.7874 0.4064)
			(stroke
				(width 0.1524)
				(type default)
			)
			(layer "F.SilkS")
		)
		(fp_line
			(start -0.67945 -0.305054)
			(end -0.12065 -0.305054)
			(stroke
				(width 0.1)
				(type default)
			)
			(layer "F.Fab")
		)
		(fp_line
			(start -0.67945 0.3048)
			(end -0.67945 -0.305054)
			(stroke
				(width 0.1)
				(type default)
			)
			(layer "F.Fab")
		)
		(fp_line
			(start -0.12065 -0.305054)
			(end -0.12065 -0.2794)
			(stroke
				(width 0.1)
				(type default)
			)
			(layer "F.Fab")
		)
		(fp_line
			(start -0.12065 -0.2794)
			(end 0.12065 -0.2794)
			(stroke
				(width 0.1)
				(type default)
			)
			(layer "F.Fab")
		)
		(fp_line
			(start -0.12065 0.2794)
			(end -0.12065 0.3048)
			(stroke
				(width 0.1)
				(type default)
			)
			(layer "F.Fab")
		)
		(fp_line
			(start -0.12065 0.3048)
			(end -0.67945 0.3048)
			(stroke
				(width 0.1)
				(type default)
			)
			(layer "F.Fab")
		)
		(fp_line
			(start 0.120396 0.2794)
			(end -0.12065 0.2794)
			(stroke
				(width 0.1)
				(type default)
			)
			(layer "F.Fab")
		)
		(fp_line
			(start 0.120396 0.3048)
			(end 0.120396 0.2794)
			(stroke
				(width 0.1)
				(type default)
			)
			(layer "F.Fab")
		)
		(fp_line
			(start 0.12065 -0.3048)
			(end 0.67945 -0.3048)
			(stroke
				(width 0.1)
				(type default)
			)
			(layer "F.Fab")
		)
		(fp_line
			(start 0.12065 -0.2794)
			(end 0.12065 -0.3048)
			(stroke
				(width 0.1)
				(type default)
			)
			(layer "F.Fab")
		)
		(fp_line
			(start 0.67945 -0.3048)
			(end 0.67945 0.3048)
			(stroke
				(width 0.1)
				(type default)
			)
			(layer "F.Fab")
		)
		(fp_line
			(start 0.67945 0.3048)
			(end 0.120396 0.3048)
			(stroke
				(width 0.1)
				(type default)
			)
			(layer "F.Fab")
		)
		(pad "1" smd circle
			(at -0.40005 0)
			(size 0 0)
			(layers "F.Cu" "F.Mask" "F.Paste")
			(net "FAN_7_PWM_OL_R")
		)
		(pad "2" smd circle
			(at 0.40005 0)
			(size 0 0)
			(layers "F.Cu" "F.Mask" "F.Paste")
			(net "GND")
		)
	)
	(footprint ""
		(layer "F.Cu")
		(at -6.938772 -209.296)
		(property "Reference" "J81"
			(at -3.5052 -5.552948 0)
			(unlocked yes)
			(layer "F.SilkS")
			(effects
				(font
					(size 0.7874 0.5842)
					(thickness 0.1524)
				)
				(justify left)
			)
		)
		(property "Value" ""
			(at 0 0 0)
			(layer "F.Fab")
			(effects
				(font
					(size 1.27 1.27)
				)
			)
		)
		(duplicate_pad_numbers_are_jumpers no)
		(fp_line
			(start -3.330702 -4.771136)
			(end 3.330702 -4.771136)
			(stroke
				(width 0.1524)
				(type default)
			)
			(layer "F.SilkS")
		)
		(fp_line
			(start 0 4.011168)
			(end -3.330702 -4.771136)
			(stroke
				(width 0.1524)
				(type default)
			)
			(layer "F.SilkS")
		)
		(fp_line
			(start 3.330702 -4.771136)
			(end 0 4.011168)
			(stroke
				(width 0.1524)
				(type default)
			)
			(layer "F.SilkS")
		)
		(fp_line
			(start -3.330702 -4.771136)
			(end 3.330702 -4.771136)
			(stroke
				(width 0.1)
				(type default)
			)
			(layer "F.Fab")
		)
		(fp_line
			(start 0 4.011168)
			(end -3.330702 -4.771136)
			(stroke
				(width 0.1)
				(type default)
			)
			(layer "F.Fab")
		)
		(fp_line
			(start 3.330702 -4.771136)
			(end 0 4.011168)
			(stroke
				(width 0.1)
				(type default)
			)
			(layer "F.Fab")
		)
		(pad "1" thru_hole circle
			(at 0 0)
			(size 2.159 2.159)
			(drill 1.7018)
			(layers "*.Cu" "*.Mask")
			(remove_unused_layers no)
			(net "GND2")
			(clearance 0.0254)
			(thermal_gap 0.0254)
		)
		(pad "2" thru_hole circle
			(at -1.27 -3.348736)
			(size 2.159 2.159)
			(drill 1.7018)
			(layers "*.Cu" "*.Mask")
			(remove_unused_layers no)
			(net "TDR_SE_50_OHM_TOP")
			(clearance 0.0254)
			(thermal_gap 0.0254)
		)
		(pad "3" thru_hole circle
			(at 1.27 -3.348736)
			(size 2.159 2.159)
			(drill 1.7018)
			(layers "*.Cu" "*.Mask")
			(remove_unused_layers no)
			(net "TDR_SE_50_OHM_TOP")
			(clearance 0.0254)
			(thermal_gap 0.0254)
		)
	)
)
